(kicad_pcb
	(version 20241229)
	(generator "pcbnew")
	(generator_version "9.0")
	(general
		(thickness 1.292)
		(legacy_teardrops no)
	)
	(paper "A4")
	(title_block
		(title "LPDDR5 Testbed")
		(date "2023-12-19")
		(rev "1.0.0")
		(comment 9 "footprints 155-160 of 160")
	)
	(layers
		(0 "F.Cu" signal)
		(4 "In1.Cu" power)
		(6 "In2.Cu" power)
		(8 "In3.Cu" signal)
		(10 "In4.Cu" signal)
		(2 "B.Cu" signal)
		(9 "F.Adhes" user "F.Adhesive")
		(11 "B.Adhes" user "B.Adhesive")
		(13 "F.Paste" user)
		(15 "B.Paste" user)
		(5 "F.SilkS" user "F.Silkscreen")
		(7 "B.SilkS" user "B.Silkscreen")
		(1 "F.Mask" user)
		(3 "B.Mask" user)
		(17 "Dwgs.User" user "User.Drawings")
		(19 "Cmts.User" user "User.Comments")
		(21 "Eco1.User" user "User.Eco1")
		(23 "Eco2.User" user "User.Eco2")
		(25 "Edge.Cuts" user)
		(27 "Margin" user)
		(31 "F.CrtYd" user "F.Courtyard")
		(29 "B.CrtYd" user "B.Courtyard")
		(35 "F.Fab" user)
		(33 "B.Fab" user)
	)
	(footprint "antmicro-footprints:C_0402_1005Metric"
		(layer "B.Cu")
		(at 142.575 79.2 180)
		(descr "Capacitor SMD 0402")
		(tags "capacitor SMD 0402")
		(property "Reference" "C77"
			(at -3.125 -0.3 0)
			(unlocked yes)
			(layer "B.SilkS")
			(effects
				(font
					(size 0.7 0.7)
					(thickness 0.15)
				)
				(justify left bottom mirror)
			)
		)
		(property "Value" "C_4u7_0402"
			(at -1.022927 -2.155213 0)
			(layer "B.Fab")
			(effects
				(font
					(size 0.7 0.7)
					(thickness 0.15)
				)
				(justify left bottom mirror)
			)
		)
		(property "Author" "Antmicro"
			(at 285.15 158.4 0)
			(layer "B.Fab")
			(hide yes)
			(effects
				(font
					(size 1 1)
					(thickness 0.15)
				)
				(justify mirror)
			)
		)
		(property "Dielectric" ""
			(at 285.15 158.4 0)
			(layer "B.Fab")
			(hide yes)
			(effects
				(font
					(size 1 1)
					(thickness 0.15)
				)
				(justify mirror)
			)
		)
		(property "License" "Apache-2.0"
			(at 285.15 158.4 0)
			(layer "B.Fab")
			(hide yes)
			(effects
				(font
					(size 1 1)
					(thickness 0.15)
				)
				(justify mirror)
			)
		)
		(property "MPN" "GRM155R61A475MEAAD"
			(at 285.15 158.4 0)
			(layer "B.Fab")
			(hide yes)
			(effects
				(font
					(size 1 1)
					(thickness 0.15)
				)
				(justify mirror)
			)
		)
		(property "Manufacturer" "Murata"
			(at 285.15 158.4 0)
			(layer "B.Fab")
			(hide yes)
			(effects
				(font
					(size 1 1)
					(thickness 0.15)
				)
				(justify mirror)
			)
		)
		(property "Val" "4u7"
			(at 285.15 158.4 0)
			(layer "B.Fab")
			(hide yes)
			(effects
				(font
					(size 1 1)
					(thickness 0.15)
				)
				(justify mirror)
			)
		)
		(property "Voltage" ""
			(at 285.15 158.4 0)
			(layer "B.Fab")
			(hide yes)
			(effects
				(font
					(size 1 1)
					(thickness 0.15)
				)
				(justify mirror)
			)
		)
		(sheetname "LPDDR5")
		(sheetfile "lpddr5.kicad_sch")
		(attr smd)
		(fp_rect
			(start -0.9659 0.481258)
			(end 0.9649 -0.458742)
			(stroke
				(width 0.05)
				(type solid)
			)
			(fill no)
			(layer "B.CrtYd")
		)
		(fp_line
			(start 0.499 0.25)
			(end 0.499 -0.248)
			(stroke
				(width 0.15)
				(type solid)
			)
			(layer "B.Fab")
		)
		(fp_line
			(start 0.499 -0.248)
			(end -0.499 -0.248)
			(stroke
				(width 0.15)
				(type solid)
			)
			(layer "B.Fab")
		)
		(fp_line
			(start -0.499 0.25)
			(end 0.499 0.25)
			(stroke
				(width 0.15)
				(type solid)
			)
			(layer "B.Fab")
		)
		(fp_line
			(start -0.499 -0.248)
			(end -0.499 0.25)
			(stroke
				(width 0.15)
				(type solid)
			)
			(layer "B.Fab")
		)
		(pad "1" smd roundrect
			(at -0.484 0 180)
			(size 0.59 0.64)
			(layers "B.Cu" "B.Mask" "B.Paste")
			(roundrect_rratio 0.25)
			(net 14 "GND")
			(pintype "passive")
		)
		(pad "2" smd roundrect
			(at 0.484 0 180)
			(size 0.59 0.64)
			(layers "B.Cu" "B.Mask" "B.Paste")
			(roundrect_rratio 0.25)
			(net 13 "+1V05")
			(pintype "passive")
		)
	)
	(footprint "antmicro-footprints:R_0402_1005Metric"
		(layer "B.Cu")
		(at 154.45 90.785 90)
		(descr "Resistor SMD 0402")
		(tags "resistor SMD 0402")
		(property "Reference" "R67"
			(at -0.115 0.45 0)
			(unlocked yes)
			(layer "B.SilkS")
			(effects
				(font
					(size 0.7 0.7)
					(thickness 0.15)
				)
				(justify right bottom mirror)
			)
		)
		(property "Value" "R_100R_0402"
			(at -1.011843 -1.772047 90)
			(layer "B.Fab")
			(effects
				(font
					(size 0.7 0.7)
					(thickness 0.15)
				)
				(justify right bottom mirror)
			)
		)
		(property "Author" "Antmicro"
			(at 245.235 -63.665 0)
			(layer "B.Fab")
			(hide yes)
			(effects
				(font
					(size 1 1)
					(thickness 0.15)
				)
				(justify mirror)
			)
		)
		(property "License" "Apache-2.0"
			(at 245.235 -63.665 0)
			(layer "B.Fab")
			(hide yes)
			(effects
				(font
					(size 1 1)
					(thickness 0.15)
				)
				(justify mirror)
			)
		)
		(property "MPN" "CR0402-FX-1000GLF"
			(at 245.235 -63.665 0)
			(layer "B.Fab")
			(hide yes)
			(effects
				(font
					(size 1 1)
					(thickness 0.15)
				)
				(justify mirror)
			)
		)
		(property "Manufacturer" "Bourns"
			(at 245.235 -63.665 0)
			(layer "B.Fab")
			(hide yes)
			(effects
				(font
					(size 1 1)
					(thickness 0.15)
				)
				(justify mirror)
			)
		)
		(property "Tolerance" "1%"
			(at 245.235 -63.665 0)
			(layer "B.Fab")
			(hide yes)
			(effects
				(font
					(size 1 1)
					(thickness 0.15)
				)
				(justify mirror)
			)
		)
		(property "Val" "100R"
			(at 245.235 -63.665 0)
			(layer "B.Fab")
			(hide yes)
			(effects
				(font
					(size 1 1)
					(thickness 0.15)
				)
				(justify mirror)
			)
		)
		(sheetname "Translators1")
		(sheetfile "translators.kicad_sch")
		(attr smd)
		(fp_rect
			(start -0.93 0.47)
			(end 0.93 -0.47)
			(stroke
				(width 0.05)
				(type solid)
			)
			(fill no)
			(layer "B.CrtYd")
		)
		(fp_rect
			(start -0.5 0.25)
			(end 0.5 -0.25)
			(stroke
				(width 0.15)
				(type solid)
			)
			(fill no)
			(layer "B.Fab")
		)
		(pad "1" smd roundrect
			(at -0.485 0 90)
			(size 0.59 0.64)
			(layers "B.Cu" "B.Mask" "B.Paste")
			(roundrect_rratio 0.25)
			(net 137 "/SODIMM/LPDDR5_IN_B.WCK1_P")
			(pintype "passive")
		)
		(pad "2" smd roundrect
			(at 0.485 0 90)
			(size 0.59 0.64)
			(layers "B.Cu" "B.Mask" "B.Paste")
			(roundrect_rratio 0.25)
			(net 111 "/LPDDR5/LPDDR5_B.WCK1_P")
			(pintype "passive")
		)
	)
	(footprint "antmicro-footprints:C_0402_1005Metric"
		(layer "B.Cu")
		(at 136.175 75.55 90)
		(descr "Capacitor SMD 0402")
		(tags "capacitor SMD 0402")
		(property "Reference" "C64"
			(at 1.35 0.025 90)
			(unlocked yes)
			(layer "B.SilkS")
			(effects
				(font
					(size 0.7 0.7)
					(thickness 0.15)
				)
				(justify right bottom mirror)
			)
		)
		(property "Value" "C_4u7_0402"
			(at -1.022927 -2.155213 90)
			(layer "B.Fab")
			(effects
				(font
					(size 0.7 0.7)
					(thickness 0.15)
				)
				(justify right bottom mirror)
			)
		)
		(property "Author" "Antmicro"
			(at 211.725 -60.625 0)
			(layer "B.Fab")
			(hide yes)
			(effects
				(font
					(size 1 1)
					(thickness 0.15)
				)
				(justify mirror)
			)
		)
		(property "Dielectric" ""
			(at 211.725 -60.625 0)
			(layer "B.Fab")
			(hide yes)
			(effects
				(font
					(size 1 1)
					(thickness 0.15)
				)
				(justify mirror)
			)
		)
		(property "License" "Apache-2.0"
			(at 211.725 -60.625 0)
			(layer "B.Fab")
			(hide yes)
			(effects
				(font
					(size 1 1)
					(thickness 0.15)
				)
				(justify mirror)
			)
		)
		(property "MPN" "GRM155R61A475MEAAD"
			(at 211.725 -60.625 0)
			(layer "B.Fab")
			(hide yes)
			(effects
				(font
					(size 1 1)
					(thickness 0.15)
				)
				(justify mirror)
			)
		)
		(property "Manufacturer" "Murata"
			(at 211.725 -60.625 0)
			(layer "B.Fab")
			(hide yes)
			(effects
				(font
					(size 1 1)
					(thickness 0.15)
				)
				(justify mirror)
			)
		)
		(property "Val" "4u7"
			(at 211.725 -60.625 0)
			(layer "B.Fab")
			(hide yes)
			(effects
				(font
					(size 1 1)
					(thickness 0.15)
				)
				(justify mirror)
			)
		)
		(property "Voltage" ""
			(at 211.725 -60.625 0)
			(layer "B.Fab")
			(hide yes)
			(effects
				(font
					(size 1 1)
					(thickness 0.15)
				)
				(justify mirror)
			)
		)
		(sheetname "LPDDR5")
		(sheetfile "lpddr5.kicad_sch")
		(attr smd)
		(fp_rect
			(start -0.9659 0.481258)
			(end 0.9649 -0.458742)
			(stroke
				(width 0.05)
				(type solid)
			)
			(fill no)
			(layer "B.CrtYd")
		)
		(fp_line
			(start 0.499 -0.248)
			(end -0.499 -0.248)
			(stroke
				(width 0.15)
				(type solid)
			)
			(layer "B.Fab")
		)
		(fp_line
			(start -0.499 -0.248)
			(end -0.499 0.25)
			(stroke
				(width 0.15)
				(type solid)
			)
			(layer "B.Fab")
		)
		(fp_line
			(start 0.499 0.25)
			(end 0.499 -0.248)
			(stroke
				(width 0.15)
				(type solid)
			)
			(layer "B.Fab")
		)
		(fp_line
			(start -0.499 0.25)
			(end 0.499 0.25)
			(stroke
				(width 0.15)
				(type solid)
			)
			(layer "B.Fab")
		)
		(pad "1" smd roundrect
			(at -0.484 0 90)
			(size 0.59 0.64)
			(layers "B.Cu" "B.Mask" "B.Paste")
			(roundrect_rratio 0.25)
			(net 14 "GND")
			(pintype "passive")
		)
		(pad "2" smd roundrect
			(at 0.484 0 90)
			(size 0.59 0.64)
			(layers "B.Cu" "B.Mask" "B.Paste")
			(roundrect_rratio 0.25)
			(net 12 "+0V9")
			(pintype "passive")
		)
	)
	(footprint "antmicro-footprints:R_0402_1005Metric"
		(layer "B.Cu")
		(at 139.75 93.85 -90)
		(descr "Resistor SMD 0402")
		(tags "resistor SMD 0402")
		(property "Reference" "R92"
			(at 0.85 -0.35 90)
			(unlocked yes)
			(layer "B.SilkS")
			(effects
				(font
					(size 0.7 0.7)
					(thickness 0.15)
				)
				(justify left bottom mirror)
			)
		)
		(property "Value" "R_100R_0402"
			(at -1.011843 -1.772047 90)
			(layer "B.Fab")
			(effects
				(font
					(size 0.7 0.7)
					(thickness 0.15)
				)
				(justify left bottom mirror)
			)
		)
		(property "Author" "Antmicro"
			(at 45.9 233.6 0)
			(layer "B.Fab")
			(hide yes)
			(effects
				(font
					(size 1 1)
					(thickness 0.15)
				)
				(justify mirror)
			)
		)
		(property "License" "Apache-2.0"
			(at 45.9 233.6 0)
			(layer "B.Fab")
			(hide yes)
			(effects
				(font
					(size 1 1)
					(thickness 0.15)
				)
				(justify mirror)
			)
		)
		(property "MPN" "CR0402-FX-1000GLF"
			(at 45.9 233.6 0)
			(layer "B.Fab")
			(hide yes)
			(effects
				(font
					(size 1 1)
					(thickness 0.15)
				)
				(justify mirror)
			)
		)
		(property "Manufacturer" "Bourns"
			(at 45.9 233.6 0)
			(layer "B.Fab")
			(hide yes)
			(effects
				(font
					(size 1 1)
					(thickness 0.15)
				)
				(justify mirror)
			)
		)
		(property "Tolerance" "1%"
			(at 45.9 233.6 0)
			(layer "B.Fab")
			(hide yes)
			(effects
				(font
					(size 1 1)
					(thickness 0.15)
				)
				(justify mirror)
			)
		)
		(property "Val" "100R"
			(at 45.9 233.6 0)
			(layer "B.Fab")
			(hide yes)
			(effects
				(font
					(size 1 1)
					(thickness 0.15)
				)
				(justify mirror)
			)
		)
		(sheetname "Translators1")
		(sheetfile "translators.kicad_sch")
		(attr smd)
		(fp_rect
			(start -0.93 0.47)
			(end 0.93 -0.47)
			(stroke
				(width 0.05)
				(type solid)
			)
			(fill no)
			(layer "B.CrtYd")
		)
		(fp_rect
			(start -0.5 0.25)
			(end 0.5 -0.25)
			(stroke
				(width 0.15)
				(type solid)
			)
			(fill no)
			(layer "B.Fab")
		)
		(pad "1" smd roundrect
			(at -0.485 0 270)
			(size 0.59 0.64)
			(layers "B.Cu" "B.Mask" "B.Paste")
			(roundrect_rratio 0.25)
			(net 100 "/LPDDR5/LPDDR5_B.CA6")
			(pintype "passive")
		)
		(pad "2" smd roundrect
			(at 0.485 0 270)
			(size 0.59 0.64)
			(layers "B.Cu" "B.Mask" "B.Paste")
			(roundrect_rratio 0.25)
			(net 14 "GND")
			(pintype "passive")
		)
	)
	(footprint "antmicro-footprints:R_0402_1005Metric"
		(layer "B.Cu")
		(at 166.45 91.95)
		(descr "Resistor SMD 0402")
		(tags "resistor SMD 0402")
		(property "Reference" "R96"
			(at 0.85 -0.15 0)
			(unlocked yes)
			(layer "B.SilkS")
			(effects
				(font
					(size 0.7 0.7)
					(thickness 0.15)
				)
				(justify right bottom mirror)
			)
		)
		(property "Value" "R_100R_0402"
			(at -1.011843 -1.772047 0)
			(layer "B.Fab")
			(effects
				(font
					(size 0.7 0.7)
					(thickness 0.15)
				)
				(justify right bottom mirror)
			)
		)
		(property "Author" "Antmicro"
			(at 0 0 0)
			(layer "B.Fab")
			(hide yes)
			(effects
				(font
					(size 1 1)
					(thickness 0.15)
				)
				(justify mirror)
			)
		)
		(property "License" "Apache-2.0"
			(at 0 0 0)
			(layer "B.Fab")
			(hide yes)
			(effects
				(font
					(size 1 1)
					(thickness 0.15)
				)
				(justify mirror)
			)
		)
		(property "MPN" "CR0402-FX-1000GLF"
			(at 0 0 0)
			(layer "B.Fab")
			(hide yes)
			(effects
				(font
					(size 1 1)
					(thickness 0.15)
				)
				(justify mirror)
			)
		)
		(property "Manufacturer" "Bourns"
			(at 0 0 0)
			(layer "B.Fab")
			(hide yes)
			(effects
				(font
					(size 1 1)
					(thickness 0.15)
				)
				(justify mirror)
			)
		)
		(property "Tolerance" "1%"
			(at 0 0 0)
			(layer "B.Fab")
			(hide yes)
			(effects
				(font
					(size 1 1)
					(thickness 0.15)
				)
				(justify mirror)
			)
		)
		(property "Val" "100R"
			(at 0 0 0)
			(layer "B.Fab")
			(hide yes)
			(effects
				(font
					(size 1 1)
					(thickness 0.15)
				)
				(justify mirror)
			)
		)
		(sheetname "Translators1")
		(sheetfile "translators.kicad_sch")
		(attr smd)
		(fp_rect
			(start -0.93 0.47)
			(end 0.93 -0.47)
			(stroke
				(width 0.05)
				(type solid)
			)
			(fill no)
			(layer "B.CrtYd")
		)
		(fp_rect
			(start -0.5 0.25)
			(end 0.5 -0.25)
			(stroke
				(width 0.15)
				(type solid)
			)
			(fill no)
			(layer "B.Fab")
		)
		(pad "1" smd roundrect
			(at -0.485 0)
			(size 0.59 0.64)
			(layers "B.Cu" "B.Mask" "B.Paste")
			(roundrect_rratio 0.25)
			(net 212 "/LPDDR5/LPDDR5_B.DMI0")
			(pintype "passive")
		)
		(pad "2" smd roundrect
			(at 0.485 0)
			(size 0.59 0.64)
			(layers "B.Cu" "B.Mask" "B.Paste")
			(roundrect_rratio 0.25)
			(net 14 "GND")
			(pintype "passive")
		)
	)
	(footprint "antmicro-footprints:C_0402_1005Metric"
		(layer "B.Cu")
		(at 127.1 80.8)
		(descr "Capacitor SMD 0402")
		(tags "capacitor SMD 0402")
		(property "Reference" "C76"
			(at -3.2 0.3 0)
			(unlocked yes)
			(layer "B.SilkS")
			(effects
				(font
					(size 0.7 0.7)
					(thickness 0.15)
				)
				(justify right bottom mirror)
			)
		)
		(property "Value" "C_4u7_0402"
			(at -1.022927 -2.155213 0)
			(layer "B.Fab")
			(effects
				(font
					(size 0.7 0.7)
					(thickness 0.15)
				)
				(justify right bottom mirror)
			)
		)
		(property "Author" "Antmicro"
			(at 0 0 0)
			(layer "B.Fab")
			(hide yes)
			(effects
				(font
					(size 1 1)
					(thickness 0.15)
				)
				(justify mirror)
			)
		)
		(property "Dielectric" ""
			(at 0 0 0)
			(layer "B.Fab")
			(hide yes)
			(effects
				(font
					(size 1 1)
					(thickness 0.15)
				)
				(justify mirror)
			)
		)
		(property "License" "Apache-2.0"
			(at 0 0 0)
			(layer "B.Fab")
			(hide yes)
			(effects
				(font
					(size 1 1)
					(thickness 0.15)
				)
				(justify mirror)
			)
		)
		(property "MPN" "GRM155R61A475MEAAD"
			(at 0 0 0)
			(layer "B.Fab")
			(hide yes)
			(effects
				(font
					(size 1 1)
					(thickness 0.15)
				)
				(justify mirror)
			)
		)
		(property "Manufacturer" "Murata"
			(at 0 0 0)
			(layer "B.Fab")
			(hide yes)
			(effects
				(font
					(size 1 1)
					(thickness 0.15)
				)
				(justify mirror)
			)
		)
		(property "Val" "4u7"
			(at 0 0 0)
			(layer "B.Fab")
			(hide yes)
			(effects
				(font
					(size 1 1)
					(thickness 0.15)
				)
				(justify mirror)
			)
		)
		(property "Voltage" ""
			(at 0 0 0)
			(layer "B.Fab")
			(hide yes)
			(effects
				(font
					(size 1 1)
					(thickness 0.15)
				)
				(justify mirror)
			)
		)
		(sheetname "LPDDR5")
		(sheetfile "lpddr5.kicad_sch")
		(attr smd)
		(fp_rect
			(start -0.9659 0.481258)
			(end 0.9649 -0.458742)
			(stroke
				(width 0.05)
				(type solid)
			)
			(fill no)
			(layer "B.CrtYd")
		)
		(fp_line
			(start -0.499 -0.248)
			(end -0.499 0.25)
			(stroke
				(width 0.15)
				(type solid)
			)
			(layer "B.Fab")
		)
		(fp_line
			(start -0.499 0.25)
			(end 0.499 0.25)
			(stroke
				(width 0.15)
				(type solid)
			)
			(layer "B.Fab")
		)
		(fp_line
			(start 0.499 -0.248)
			(end -0.499 -0.248)
			(stroke
				(width 0.15)
				(type solid)
			)
			(layer "B.Fab")
		)
		(fp_line
			(start 0.499 0.25)
			(end 0.499 -0.248)
			(stroke
				(width 0.15)
				(type solid)
			)
			(layer "B.Fab")
		)
		(pad "1" smd roundrect
			(at -0.484 0)
			(size 0.59 0.64)
			(layers "B.Cu" "B.Mask" "B.Paste")
			(roundrect_rratio 0.25)
			(net 14 "GND")
			(pintype "passive")
		)
		(pad "2" smd roundrect
			(at 0.484 0)
			(size 0.59 0.64)
			(layers "B.Cu" "B.Mask" "B.Paste")
			(roundrect_rratio 0.25)
			(net 13 "+1V05")
			(pintype "passive")
		)
	)
)
